# S9S_MB_2U (Grand Teton) — schematic netlist excerpt (pin names and nets, part order shuffled) for the footprints in the layout excerpt that follows; sources: Cadence DE-HDL packaged netlist, KiCad conversion of 03242023_DA0F0TMBIJ0_F0T_Motherboard_J_brd_V01_OCP.brd

PU287  MP5991GLUZ  MP5991GLU-Z IC  pkg LGA32_TH_0-5_5X5  page 302
  VOUT1  = P12V_AUX
  VOUT2  = P12V_AUX
  D_OC  = HSC_D_OC_1
  \on\  = HSC_ON
  GOK  = HSC_FAULT
  FLT_TYPE  = HSC_FLT_TYPE_1
  NC1  = HSC_NC1_1
  MODE  = HSC_MODE_1
  VIN1  = P12V_PSU
  VIN2  = P12V_PSU
  VIN3  = P12V_PSU
  VIN4  = P12V_PSU
  VIN5  = P12V_PSU
  VIN6  = P12V_PSU
  VIN7  = P12V_PSU
  VIN8  = P12V_PSU
  SCREF_OCWREF  = HSC_SCREF_1
  VTEMP  = HSC_VTEMP
  SS  = HSC_SS
  GND  = AGND_HSC
  VDD33  = HSC_VDD_R_1
  IMON  = HSC_IMON
  CS  = HSC_CS_1
  OCREF  = HSC_OCREF
  VOUT3  = P12V_AUX
  VOUT4  = P12V_AUX
  VOUT5  = P12V_AUX
  VOUT6  = P12V_AUX
  VOUT7  = P12V_AUX
  VOUT8  = P12V_AUX
  VOUT9  = P12V_AUX
  VOUT10  = P12V_AUX
  VIN9  = P12V_PSU

(kicad_pcb
	(version 20260206)
	(generator "pcbnew")
	(generator_version "10.0")
	(general
		(thickness 1.6)
		(legacy_teardrops no)
	)
	(paper "A4")
	(title_block
		(title "03242023_DA0F0TMBIJ0_F0T_Motherboard_J_brd_V01_OCP.brd")
		(comment 1 "Grand Teton / footprints 1181-1181 of 6105")
	)
	(layers
		(0 "F.Cu" signal "TOP")
		(4 "In1.Cu" signal "GND")
		(6 "In2.Cu" signal "IN1")
		(8 "In3.Cu" signal "GND1")
		(10 "In4.Cu" signal "IN2")
		(12 "In5.Cu" signal "GND2")
		(14 "In6.Cu" signal "IN3")
		(16 "In7.Cu" signal "GND3")
		(18 "In8.Cu" signal "VCC")
		(20 "In9.Cu" signal "VCC1")
		(22 "In10.Cu" signal "GND4")
		(24 "In11.Cu" signal "IN4")
		(26 "In12.Cu" signal "GND5")
		(28 "In13.Cu" signal "IN5")
		(30 "In14.Cu" signal "GND6")
		(32 "In15.Cu" signal "IN6")
		(34 "In16.Cu" signal "GND7")
		(2 "B.Cu" signal "BOTTOM")
		(9 "F.Adhes" user "F.Adhesive")
		(11 "B.Adhes" user "B.Adhesive")
		(13 "F.Paste" user "Package Geometry/Pastemask Top")
		(15 "B.Paste" user "Package Geometry/Pastemask Bottom")
		(5 "F.SilkS" user "Ref Des/Silkscreen Top")
		(7 "B.SilkS" user "Ref Des/Silkscreen Bottom")
		(1 "F.Mask" user "Board Geometry/Soldermask Top")
		(3 "B.Mask" user "Board Geometry/Soldermask Bottom")
		(17 "Dwgs.User" user "User.Drawings")
		(19 "Cmts.User" user "User.Comments")
		(21 "Eco1.User" user "User.Eco1")
		(23 "Eco2.User" user "User.Eco2")
		(25 "Edge.Cuts" user "Board Geometry/Outline")
		(27 "Margin" user)
		(31 "F.CrtYd" user "Package Geometry/Place Bound Top")
		(29 "B.CrtYd" user "Package Geometry/Place Bound Bottom")
		(35 "F.Fab" user "Ref Des/Assembly Top")
		(33 "B.Fab" user "Ref Des/Assembly Bottom")
	)
	(footprint ""
		(layer "F.Cu")
		(at 200.172066 -402.722842 180)
		(property "Reference" "PU287"
			(at 0.468376 7.808468 0)
			(unlocked yes)
			(layer "F.SilkS")
			(effects
				(font
					(size 0.7874 0.5842)
					(thickness 0.1524)
				)
			)
		)
		(property "Value" ""
			(at 0 0 180)
			(layer "F.Fab")
			(effects
				(font
					(size 1.27 1.27)
				)
			)
		)
		(duplicate_pad_numbers_are_jumpers no)
		(fp_line
			(start 2.567686 2.567686)
			(end 2.567686 -2.567686)
			(stroke
				(width 0.1524)
				(type default)
			)
			(layer "F.SilkS")
		)
		(fp_line
			(start 2.567686 -2.567686)
			(end -2.567686 -2.567686)
			(stroke
				(width 0.1524)
				(type default)
			)
			(layer "F.SilkS")
		)
		(fp_line
			(start -2.567686 2.567686)
			(end 2.567686 2.567686)
			(stroke
				(width 0.1524)
				(type default)
			)
			(layer "F.SilkS")
		)
		(fp_line
			(start -2.567686 -2.567686)
			(end -2.567686 2.567686)
			(stroke
				(width 0.1524)
				(type default)
			)
			(layer "F.SilkS")
		)
		(fp_poly
			(pts
				(xy -3.055366 -3.35534) (xy -2.69621 -2.277618) (xy -3.773678 -2.636774)
			)
			(stroke
				(width 0)
				(type default)
			)
			(fill yes)
			(layer "F.SilkS")
		)
		(fp_line
			(start 2.549906 2.549906)
			(end 2.549906 -2.549906)
			(stroke
				(width 0.1)
				(type default)
			)
			(layer "F.Fab")
		)
		(fp_line
			(start 2.549906 -2.549906)
			(end -2.549906 -2.549906)
			(stroke
				(width 0.1)
				(type default)
			)
			(layer "F.Fab")
		)
		(fp_line
			(start -2.549906 2.549906)
			(end 2.549906 2.549906)
			(stroke
				(width 0.1)
				(type default)
			)
			(layer "F.Fab")
		)
		(fp_line
			(start -2.549906 -2.549906)
			(end -2.549906 2.549906)
			(stroke
				(width 0.1)
				(type default)
			)
			(layer "F.Fab")
		)
		(fp_poly
			(pts
				(xy -3.806698 -2.25806) (xy -3.806698 -1.24206) (xy -2.790698 -1.75006)
			)
			(stroke
				(width 0)
				(type default)
			)
			(fill yes)
			(layer "F.Fab")
		)
		(pad "1" smd rect
			(at -2.250186 -1.75006 270)
			(size 0.254 0.3556)
			(layers "F.Cu" "F.Mask" "F.Paste")
			(net "P12V_AUX")
		)
		(pad "2" smd rect
			(at -2.237486 -1.249934 270)
			(size 0.254 0.381)
			(layers "F.Cu" "F.Mask" "F.Paste")
			(net "P12V_AUX")
		)
		(pad "3" smd rect
			(at -2.237486 -0.750062 270)
			(size 0.254 0.381)
			(layers "F.Cu" "F.Mask" "F.Paste")
			(net "HSC_D_OC_1")
		)
		(pad "4" smd rect
			(at -2.237486 -0.249936 270)
			(size 0.254 0.381)
			(layers "F.Cu" "F.Mask" "F.Paste")
			(net "HSC_ON")
		)
		(pad "5" smd rect
			(at -2.237486 0.249936 270)
			(size 0.254 0.381)
			(layers "F.Cu" "F.Mask" "F.Paste")
			(net "HSC_FAULT")
		)
		(pad "6" smd rect
			(at -2.237486 0.750062 270)
			(size 0.254 0.381)
			(layers "F.Cu" "F.Mask" "F.Paste")
			(net "HSC_FLT_TYPE_1")
		)
		(pad "7" smd rect
			(at -2.237486 1.249934 270)
			(size 0.254 0.381)
			(layers "F.Cu" "F.Mask" "F.Paste")
			(net "HSC_NC1_1")
		)
		(pad "8" smd rect
			(at -2.250186 1.75006 270)
			(size 0.254 0.3556)
			(layers "F.Cu" "F.Mask" "F.Paste")
			(net "HSC_MODE_1")
		)
		(pad "9" smd rect
			(at -1.75006 2.250186 180)
			(size 0.254 0.3556)
			(layers "F.Cu" "F.Mask" "F.Paste")
			(net "P12V_PSU")
		)
		(pad "10" smd rect
			(at -1.249934 2.237486 180)
			(size 0.254 0.381)
			(layers "F.Cu" "F.Mask" "F.Paste")
			(net "P12V_PSU")
		)
		(pad "11" smd rect
			(at -0.750062 2.237486 180)
			(size 0.254 0.381)
			(layers "F.Cu" "F.Mask" "F.Paste")
			(net "P12V_PSU")
		)
		(pad "12" smd rect
			(at -0.249936 2.237486 180)
			(size 0.254 0.381)
			(layers "F.Cu" "F.Mask" "F.Paste")
			(net "P12V_PSU")
		)
		(pad "13" smd rect
			(at 0.249936 2.237486 180)
			(size 0.254 0.381)
			(layers "F.Cu" "F.Mask" "F.Paste")
			(net "P12V_PSU")
		)
		(pad "14" smd rect
			(at 0.750062 2.237486 180)
			(size 0.254 0.381)
			(layers "F.Cu" "F.Mask" "F.Paste")
			(net "P12V_PSU")
		)
		(pad "15" smd rect
			(at 1.249934 2.237486 180)
			(size 0.254 0.381)
			(layers "F.Cu" "F.Mask" "F.Paste")
			(net "P12V_PSU")
		)
		(pad "16" smd rect
			(at 1.75006 2.250186 180)
			(size 0.254 0.3556)
			(layers "F.Cu" "F.Mask" "F.Paste")
			(net "P12V_PSU")
		)
		(pad "17" smd rect
			(at 2.250186 1.75006 270)
			(size 0.254 0.3556)
			(layers "F.Cu" "F.Mask" "F.Paste")
			(net "HSC_SCREF_1")
		)
		(pad "18" smd rect
			(at 2.237486 1.249934 270)
			(size 0.254 0.381)
			(layers "F.Cu" "F.Mask" "F.Paste")
			(net "HSC_VTEMP")
		)
		(pad "19" smd rect
			(at 2.237486 0.750062 270)
			(size 0.254 0.381)
			(layers "F.Cu" "F.Mask" "F.Paste")
			(net "HSC_SS")
		)
		(pad "20" smd rect
			(at 2.237486 0.249936 270)
			(size 0.254 0.381)
			(layers "F.Cu" "F.Mask" "F.Paste")
			(net "AGND_HSC")
		)
		(pad "21" smd rect
			(at 2.237486 -0.249936 270)
			(size 0.254 0.381)
			(layers "F.Cu" "F.Mask" "F.Paste")
			(net "HSC_VDD_R_1")
		)
		(pad "22" smd rect
			(at 2.237486 -0.750062 270)
			(size 0.254 0.381)
			(layers "F.Cu" "F.Mask" "F.Paste")
			(net "HSC_IMON")
		)
		(pad "23" smd rect
			(at 2.237486 -1.249934 270)
			(size 0.254 0.381)
			(layers "F.Cu" "F.Mask" "F.Paste")
			(net "HSC_CS_1")
		)
		(pad "24" smd rect
			(at 2.250186 -1.75006 270)
			(size 0.254 0.3556)
			(layers "F.Cu" "F.Mask" "F.Paste")
			(net "HSC_OCREF")
		)
		(pad "25" smd rect
			(at 1.75006 -2.250186 180)
			(size 0.254 0.3556)
			(layers "F.Cu" "F.Mask" "F.Paste")
			(net "P12V_AUX")
		)
		(pad "26" smd rect
			(at 1.249934 -2.237486 180)
			(size 0.254 0.381)
			(layers "F.Cu" "F.Mask" "F.Paste")
			(net "P12V_AUX")
		)
		(pad "27" smd rect
			(at 0.750062 -2.237486 180)
			(size 0.254 0.381)
			(layers "F.Cu" "F.Mask" "F.Paste")
			(net "P12V_AUX")
		)
		(pad "28" smd rect
			(at 0.249936 -2.237486 180)
			(size 0.254 0.381)
			(layers "F.Cu" "F.Mask" "F.Paste")
			(net "P12V_AUX")
		)
		(pad "29" smd rect
			(at -0.249936 -2.237486 180)
			(size 0.254 0.381)
			(layers "F.Cu" "F.Mask" "F.Paste")
			(net "P12V_AUX")
		)
		(pad "30" smd rect
			(at -0.750062 -2.237486 180)
			(size 0.254 0.381)
			(layers "F.Cu" "F.Mask" "F.Paste")
			(net "P12V_AUX")
		)
		(pad "31" smd rect
			(at -1.249934 -2.237486 180)
			(size 0.254 0.381)
			(layers "F.Cu" "F.Mask" "F.Paste")
			(net "P12V_AUX")
		)
		(pad "32" smd rect
			(at -1.75006 -2.250186 180)
			(size 0.254 0.3556)
			(layers "F.Cu" "F.Mask" "F.Paste")
			(net "P12V_AUX")
		)
		(pad "33" smd rect
			(at 0 0 180)
			(size 3.4036 3.4036)
			(layers "F.Cu" "F.Mask" "F.Paste")
			(net "P12V_PSU")
		)
		(zone
			(layer "F.Cu")
			(hatch none 0.5)
			(connect_pads
				(clearance 0)
			)
			(min_thickness 0.25)
			(keepout
				(tracks not_allowed)
				(vias allowed)
				(pads allowed)
				(copperpour not_allowed)
				(footprints allowed)
			)
			(placement
				(enabled no)
				(sheetname "")
			)
			(fill
				(thermal_gap 0.5)
				(thermal_bridge_width 0.5)
				(island_removal_mode 0)
			)
			(polygon
				(pts
					(xy 202.193652 -401.275042) (xy 202.193652 -400.845528) (xy 202.04938 -400.701256) (xy 201.619866 -400.701256)
					(xy 201.619866 -400.726656) (xy 198.724266 -400.726656) (xy 198.724266 -400.701256) (xy 198.15048 -400.701256)
					(xy 198.15048 -401.275042) (xy 198.17588 -401.275042) (xy 198.17588 -404.170642) (xy 198.15048 -404.170642)
					(xy 198.15048 -404.475442) (xy 198.419466 -404.475442) (xy 198.419466 -400.970242) (xy 201.924666 -400.970242)
					(xy 201.924666 -403.230842) (xy 202.168252 -403.230842) (xy 202.168252 -401.275042)
				)
			)
		)
	)
)
